# T6G (Grand Teton) — schematic netlist excerpt (pin names and nets, part order shuffled) for the footprints in the layout excerpt that follows; sources: Cadence DE-HDL packaged netlist, KiCad conversion of 04192023_DAF0TMB3IC0_F0TG_MB_C_brd_V02_OCP.brd

C2643  Q_CAP  22UF 4V 20% X6S  pkg C0402  page 70 : A = PVDDIO_P0 ; B = GND
R6733  Q_RES  0 5% CHIP  pkg 0201LF  page 332 : A = NCF_CPU1_P1_GND ; B = GND
R3209  Q_RES  22 1% EMPTY  pkg 0402LF  page 138 : A = OCP_V3_2_RBT_ARB_IN_R ; B = OCP_V3_2_RBT_ARB_IN

(kicad_pcb
	(version 20260206)
	(generator "pcbnew")
	(generator_version "10.0")
	(general
		(thickness 1.6)
		(legacy_teardrops no)
	)
	(paper "A4")
	(title_block
		(title "04192023_DAF0TMB3IC0_F0TG_MB_C_brd_V02_OCP.brd")
		(comment 1 "Grand Teton / footprints 5705-5707 of 8354")
	)
	(layers
		(0 "F.Cu" signal "TOP")
		(4 "In1.Cu" signal "GND")
		(6 "In2.Cu" signal "IN1")
		(8 "In3.Cu" signal "GND1")
		(10 "In4.Cu" signal "IN2")
		(12 "In5.Cu" signal "GND2")
		(14 "In6.Cu" signal "IN3")
		(16 "In7.Cu" signal "GND3")
		(18 "In8.Cu" signal "VCC")
		(20 "In9.Cu" signal "VCC1")
		(22 "In10.Cu" signal "GND4")
		(24 "In11.Cu" signal "IN4")
		(26 "In12.Cu" signal "GND5")
		(28 "In13.Cu" signal "IN5")
		(30 "In14.Cu" signal "GND6")
		(32 "In15.Cu" signal "IN6")
		(34 "In16.Cu" signal "GND7")
		(2 "B.Cu" signal "BOTTOM")
		(9 "F.Adhes" user "F.Adhesive")
		(11 "B.Adhes" user "B.Adhesive")
		(13 "F.Paste" user "Package Geometry/Pastemask Top")
		(15 "B.Paste" user "Package Geometry/Pastemask Bottom")
		(5 "F.SilkS" user "Ref Des/Silkscreen Top")
		(7 "B.SilkS" user "Ref Des/Silkscreen Bottom")
		(1 "F.Mask" user "Board Geometry/Soldermask Top")
		(3 "B.Mask" user "Board Geometry/Soldermask Bottom")
		(17 "Dwgs.User" user "User.Drawings")
		(19 "Cmts.User" user "User.Comments")
		(21 "Eco1.User" user "User.Eco1")
		(23 "Eco2.User" user "User.Eco2")
		(25 "Edge.Cuts" user "Board Geometry/Outline")
		(27 "Margin" user)
		(31 "F.CrtYd" user "Package Geometry/Place Bound Top")
		(29 "B.CrtYd" user "Package Geometry/Place Bound Bottom")
		(35 "F.Fab" user "Ref Des/Assembly Top")
		(33 "B.Fab" user "Ref Des/Assembly Bottom")
	)
	(footprint ""
		(layer "B.Cu")
		(at 348.418912 -257.930142 180)
		(property "Reference" "C2643"
			(at 0 0 0)
			(layer "B.SilkS")
			(hide yes)
			(effects
				(font
					(size 1.27 1.27)
				)
				(justify mirror)
			)
		)
		(property "Value" ""
			(at 0 0 0)
			(layer "B.Fab")
			(effects
				(font
					(size 1.27 1.27)
				)
				(justify mirror)
			)
		)
		(duplicate_pad_numbers_are_jumpers no)
		(fp_line
			(start 0.7874 0.4064)
			(end 0.7874 -0.4064)
			(stroke
				(width 0.1524)
				(type default)
			)
			(layer "B.SilkS")
		)
		(fp_line
			(start 0.7874 -0.4064)
			(end -0.7874 -0.4064)
			(stroke
				(width 0.1524)
				(type default)
			)
			(layer "B.SilkS")
		)
		(fp_line
			(start -0.7874 0.4064)
			(end 0.7874 0.4064)
			(stroke
				(width 0.1524)
				(type default)
			)
			(layer "B.SilkS")
		)
		(fp_line
			(start -0.7874 -0.4064)
			(end -0.7874 0.4064)
			(stroke
				(width 0.1524)
				(type default)
			)
			(layer "B.SilkS")
		)
		(fp_line
			(start 0.67945 0.3048)
			(end 0.67945 -0.305054)
			(stroke
				(width 0.1)
				(type default)
			)
			(layer "B.Fab")
		)
		(fp_line
			(start 0.67945 -0.305054)
			(end 0.12065 -0.305054)
			(stroke
				(width 0.1)
				(type default)
			)
			(layer "B.Fab")
		)
		(fp_line
			(start 0.12065 0.3048)
			(end 0.67945 0.3048)
			(stroke
				(width 0.1)
				(type default)
			)
			(layer "B.Fab")
		)
		(fp_line
			(start 0.12065 0.2794)
			(end 0.12065 0.3048)
			(stroke
				(width 0.1)
				(type default)
			)
			(layer "B.Fab")
		)
		(fp_line
			(start 0.12065 -0.2794)
			(end -0.12065 -0.2794)
			(stroke
				(width 0.1)
				(type default)
			)
			(layer "B.Fab")
		)
		(fp_line
			(start 0.12065 -0.305054)
			(end 0.12065 -0.2794)
			(stroke
				(width 0.1)
				(type default)
			)
			(layer "B.Fab")
		)
		(fp_line
			(start -0.120396 0.3048)
			(end -0.120396 0.2794)
			(stroke
				(width 0.1)
				(type default)
			)
			(layer "B.Fab")
		)
		(fp_line
			(start -0.120396 0.2794)
			(end 0.12065 0.2794)
			(stroke
				(width 0.1)
				(type default)
			)
			(layer "B.Fab")
		)
		(fp_line
			(start -0.12065 -0.2794)
			(end -0.12065 -0.3048)
			(stroke
				(width 0.1)
				(type default)
			)
			(layer "B.Fab")
		)
		(fp_line
			(start -0.12065 -0.3048)
			(end -0.67945 -0.3048)
			(stroke
				(width 0.1)
				(type default)
			)
			(layer "B.Fab")
		)
		(fp_line
			(start -0.67945 0.3048)
			(end -0.120396 0.3048)
			(stroke
				(width 0.1)
				(type default)
			)
			(layer "B.Fab")
		)
		(fp_line
			(start -0.67945 -0.3048)
			(end -0.67945 0.3048)
			(stroke
				(width 0.1)
				(type default)
			)
			(layer "B.Fab")
		)
		(pad "1" smd circle
			(at 0.40005 0)
			(size 0 0)
			(layers "B.Cu" "B.Mask" "B.Paste")
			(net "PVDDIO_P0")
		)
		(pad "2" smd circle
			(at -0.40005 0)
			(size 0 0)
			(layers "B.Cu" "B.Mask" "B.Paste")
			(net "GND")
		)
	)
	(footprint ""
		(layer "B.Cu")
		(at 203.045314 -77.231748)
		(property "Reference" "R3209"
			(at 0 0 0)
			(layer "B.SilkS")
			(hide yes)
			(effects
				(font
					(size 1.27 1.27)
				)
				(justify mirror)
			)
		)
		(property "Value" ""
			(at 0 0 0)
			(layer "B.Fab")
			(effects
				(font
					(size 1.27 1.27)
				)
				(justify mirror)
			)
		)
		(duplicate_pad_numbers_are_jumpers no)
		(fp_line
			(start -0.7874 -0.4064)
			(end -0.7874 0.4064)
			(stroke
				(width 0.1524)
				(type default)
			)
			(layer "B.SilkS")
		)
		(fp_line
			(start -0.7874 0.4064)
			(end 0.7874 0.4064)
			(stroke
				(width 0.1524)
				(type default)
			)
			(layer "B.SilkS")
		)
		(fp_line
			(start 0.7874 -0.4064)
			(end -0.7874 -0.4064)
			(stroke
				(width 0.1524)
				(type default)
			)
			(layer "B.SilkS")
		)
		(fp_line
			(start 0.7874 0.4064)
			(end 0.7874 -0.4064)
			(stroke
				(width 0.1524)
				(type default)
			)
			(layer "B.SilkS")
		)
		(fp_line
			(start -0.67945 -0.3048)
			(end -0.67945 0.3048)
			(stroke
				(width 0.1)
				(type default)
			)
			(layer "B.Fab")
		)
		(fp_line
			(start -0.67945 0.3048)
			(end -0.120396 0.3048)
			(stroke
				(width 0.1)
				(type default)
			)
			(layer "B.Fab")
		)
		(fp_line
			(start -0.12065 -0.3048)
			(end -0.67945 -0.3048)
			(stroke
				(width 0.1)
				(type default)
			)
			(layer "B.Fab")
		)
		(fp_line
			(start -0.12065 -0.2794)
			(end -0.12065 -0.3048)
			(stroke
				(width 0.1)
				(type default)
			)
			(layer "B.Fab")
		)
		(fp_line
			(start -0.120396 0.2794)
			(end 0.12065 0.2794)
			(stroke
				(width 0.1)
				(type default)
			)
			(layer "B.Fab")
		)
		(fp_line
			(start -0.120396 0.3048)
			(end -0.120396 0.2794)
			(stroke
				(width 0.1)
				(type default)
			)
			(layer "B.Fab")
		)
		(fp_line
			(start 0.12065 -0.305054)
			(end 0.12065 -0.2794)
			(stroke
				(width 0.1)
				(type default)
			)
			(layer "B.Fab")
		)
		(fp_line
			(start 0.12065 -0.2794)
			(end -0.12065 -0.2794)
			(stroke
				(width 0.1)
				(type default)
			)
			(layer "B.Fab")
		)
		(fp_line
			(start 0.12065 0.2794)
			(end 0.12065 0.3048)
			(stroke
				(width 0.1)
				(type default)
			)
			(layer "B.Fab")
		)
		(fp_line
			(start 0.12065 0.3048)
			(end 0.67945 0.3048)
			(stroke
				(width 0.1)
				(type default)
			)
			(layer "B.Fab")
		)
		(fp_line
			(start 0.67945 -0.305054)
			(end 0.12065 -0.305054)
			(stroke
				(width 0.1)
				(type default)
			)
			(layer "B.Fab")
		)
		(fp_line
			(start 0.67945 0.3048)
			(end 0.67945 -0.305054)
			(stroke
				(width 0.1)
				(type default)
			)
			(layer "B.Fab")
		)
		(pad "1" smd circle
			(at 0.40005 0 180)
			(size 0 0)
			(layers "B.Cu" "B.Mask" "B.Paste")
			(net "OCP_V3_2_RBT_ARB_IN_R")
		)
		(pad "2" smd circle
			(at -0.40005 0 180)
			(size 0 0)
			(layers "B.Cu" "B.Mask" "B.Paste")
			(net "OCP_V3_2_RBT_ARB_IN")
		)
	)
	(footprint ""
		(layer "B.Cu")
		(at 102.580948 -382.8796 180)
		(property "Reference" "R6733"
			(at 0 0 0)
			(layer "B.SilkS")
			(hide yes)
			(effects
				(font
					(size 1.27 1.27)
				)
				(justify mirror)
			)
		)
		(property "Value" ""
			(at 0 0 0)
			(layer "B.Fab")
			(effects
				(font
					(size 1.27 1.27)
				)
				(justify mirror)
			)
		)
		(duplicate_pad_numbers_are_jumpers no)
		(fp_line
			(start 0.32512 0.175006)
			(end 0.32512 -0.175006)
			(stroke
				(width 0.1)
				(type default)
			)
			(layer "B.Fab")
		)
		(fp_line
			(start 0.32512 -0.175006)
			(end -0.32512 -0.175006)
			(stroke
				(width 0.1)
				(type default)
			)
			(layer "B.Fab")
		)
		(fp_line
			(start -0.32512 0.175006)
			(end 0.32512 0.175006)
			(stroke
				(width 0.1)
				(type default)
			)
			(layer "B.Fab")
		)
		(fp_line
			(start -0.32512 -0.175006)
			(end -0.32512 0.175006)
			(stroke
				(width 0.1)
				(type default)
			)
			(layer "B.Fab")
		)
		(pad "1" smd rect
			(at 0.2667 0)
			(size 0.3048 0.381)
			(layers "B.Cu" "B.Mask" "B.Paste")
			(net "NCF_CPU1_P1_GND")
		)
		(pad "2" smd rect
			(at -0.2667 0 180)
			(size 0.3048 0.381)
			(layers "B.Cu" "B.Mask" "B.Paste")
			(net "GND")
		)
	)
)
